FILE_TYPE = CONNECTIVITY;
{Allegro Design Entry HDL 17.4-2019 S026 (4007227) 1/17/2022}
"PAGE_NUMBER" = 443;
0"NC";
1"P0V9_CPU1_RT1_2A\g";
2"GND\g";
3"P0V9_CPU1_RT_2D\g";
4"GND\g";
5"P1V8_CPU1_RT_1D\g";
6"GND\g";
7"P1V8_CPU1_RT1_1A\g";
8"GND\g";
9"GND\g";
10"GND\g";
11"P1V8_CPU1_RT1_1A_1D\g";
12"GND\g";
13"P0V9_CPU1_RT1_2A_2D\g";
%"Q_RES"
"2","(-4325,2575)","2","pure_quanta","I10";
;
LOCATION"R705"
$SEC"1"
CDS_SEC"1"
WATTAGE"1/4W"
MATERIAL"EMPTY"
PACK_TYPE"0603LF"
VALUE"0"
TOLERANCE"5%"
CDS_LIB"pure_quanta"
PART_NUMBER"CS00006J900";
"A"
$PN"1"3;
"B"
$PN"2"13;
%"Q_RES"
"1","(-3950,2300)","0","pure_quanta","I11";
;
LOCATION"R712"
$SEC"1"
CDS_SEC"1"
PACK_TYPE"0603LF"
TOLERANCE"5%"
VALUE"0"
MATERIAL"CHIP"
WATTAGE"1/4W"
CDS_LIB"pure_quanta"
PART_NUMBER"CS00006J900";
"B"
$PN"2"1;
"A"
$PN"1"13;
%"Q_INDUCTOR"
"1","(-7800,4275)","0","pure_quanta","I12";
;
LOCATION"L5"
$SEC"1"
CDS_SEC"1"
PACK_TYPE"SMLF"
MATERIAL"IND"
VALUE"BLM21SN300SN1D/5A"
CDS_LIB"pure_quanta"
NEEDS_NO_SIZE"TRUE"
PART_NUMBER"CX300SN1000";
"1"
$PN"1"5;
"2"
$PN"2"7;
%"Q_CAP"
"1","(-7225,4000)","0","pure_quanta","I13";
;
LOCATION"C103"
$SEC"1"
CDS_SEC"1"
VOLTAGE"4V"
MATERIAL"X6S"
TOLERANCE"20%"
PACK_TYPE"C0805"
VALUE"100UF"
CDS_LIB"pure_quanta"
PART_NUMBER"CH710KMEA01";
"B"
$PN"2"8;
"A"
$PN"1"7;
%"Q_CAP"
"1","(-7000,4000)","0","pure_quanta","I14";
;
LOCATION"C111"
$SEC"1"
CDS_SEC"1"
VALUE"22UF"
VOLTAGE"4V"
TOLERANCE"20%"
MATERIAL"X6S"
PACK_TYPE"C0402"
CDS_LIB"pure_quanta"
PART_NUMBER"CH622KMEB02";
"B"
$PN"2"8;
"A"
$PN"1"7;
%"P1V0"
"1","(-7325,4475)","0","pure_quanta_power","I15";
;
HDL_POWER"P1V8_CPU1_RT1_1A"
CDS_LIB"pure_quanta_power";
"A"7;
%"Q_CAP"
"1","(-7075,4825)","0","pure_quanta","I16";
;
LOCATION"C102"
$SEC"1"
CDS_SEC"1"
PACK_TYPE"C0805"
VOLTAGE"4V"
TOLERANCE"20%"
MATERIAL"X6S"
VALUE"100UF"
CDS_LIB"pure_quanta"
PART_NUMBER"CH710KMEA01";
"B"
$PN"2"6;
"A"
$PN"1"5;
%"Q_CAP"
"1","(-6800,4000)","0","pure_quanta","I17";
;
LOCATION"C199"
$SEC"1"
CDS_SEC"1"
TOLERANCE"20%"
MATERIAL"X6S"
PACK_TYPE"C0402"
VALUE"10UF"
VOLTAGE"6.3V"
CDS_LIB"pure_quanta"
PART_NUMBER"CH6101MEB01";
"B"
$PN"2"8;
"A"
$PN"1"7;
%"Q_CAP"
"1","(-6600,4000)","0","pure_quanta","I18";
;
LOCATION"C195"
$SEC"1"
CDS_SEC"1"
VALUE"4.7UF"
PACK_TYPE"0402"
TOLERANCE"20%"
VOLTAGE"6.3V"
MATERIAL"X6S"
CDS_LIB"pure_quanta"
PART_NUMBER"CH5471MEB01";
"B"
$PN"2"8;
"A"
$PN"1"7;
%"UNIVERSAL_GND"
"1","(-6400,4525)","0","pure_quanta_power","I19";
;
CDS_LIB"pure_quanta_power"
HDL_POWER"GND";
"A"6;
%"Q_CAP"
"1","(-6375,4000)","0","pure_quanta","I20";
;
LOCATION"C202"
$SEC"1"
CDS_SEC"1"
VOLTAGE"4V"
VALUE"1UF"
MATERIAL"X6S"
PACK_TYPE"0201"
TOLERANCE"20%"
CDS_LIB"pure_quanta"
PART_NUMBER"CH-10KMEE00";
"B"
$PN"2"8;
"A"
$PN"1"7;
%"UNIVERSAL_GND"
"1","(-6175,3675)","0","pure_quanta_power","I21";
;
CDS_LIB"pure_quanta_power"
HDL_POWER"GND";
"A"8;
%"Q_CAP"
"1","(-6175,4000)","0","pure_quanta","I22";
;
LOCATION"C204"
$SEC"1"
CDS_SEC"1"
VOLTAGE"4V"
PACK_TYPE"0201"
MATERIAL"X6S"
TOLERANCE"20%"
VALUE"1UF"
CDS_LIB"pure_quanta"
PART_NUMBER"CH-10KMEE00";
"B"
$PN"2"8;
"A"
$PN"1"7;
%"Q_CAP"
"1","(-5950,4000)","0","pure_quanta","I23";
;
LOCATION"C205"
$SEC"1"
CDS_SEC"1"
MATERIAL"X7S"
PACK_TYPE"C0201"
VOLTAGE"10V"
VALUE"0.1UF"
TOLERANCE"10%"
CDS_LIB"pure_quanta"
PART_NUMBER"CH4102K6E00";
"B"
$PN"2"8;
"A"
$PN"1"7;
%"Q_CAP"
"1","(-6825,4825)","0","pure_quanta","I24";
;
LOCATION"C110"
$SEC"1"
CDS_SEC"1"
VALUE"22UF"
MATERIAL"X6S"
PACK_TYPE"C0402"
TOLERANCE"20%"
VOLTAGE"4V"
CDS_LIB"pure_quanta"
PART_NUMBER"CH622KMEB02";
"B"
$PN"2"6;
"A"
$PN"1"5;
%"Q_CAP"
"1","(-6575,4800)","0","pure_quanta","I25";
;
LOCATION"C127"
$SEC"1"
CDS_SEC"1"
MATERIAL"X6S"
VOLTAGE"6.3V"
TOLERANCE"20%"
VALUE"10UF"
PACK_TYPE"C0402"
CDS_LIB"pure_quanta"
PART_NUMBER"CH6101MEB01";
"B"
$PN"2"6;
"A"
$PN"1"5;
%"Q_CAP"
"1","(-6325,4800)","0","pure_quanta","I26";
;
LOCATION"C200"
$SEC"1"
CDS_SEC"1"
VOLTAGE"6.3V"
VALUE"4.7UF"
TOLERANCE"20%"
MATERIAL"X6S"
PACK_TYPE"0402"
CDS_LIB"pure_quanta"
PART_NUMBER"CH5471MEB01";
"B"
$PN"2"6;
"A"
$PN"1"5;
%"Q_CAP"
"1","(-5700,4000)","0","pure_quanta","I27";
;
LOCATION"C217"
$SEC"1"
CDS_SEC"1"
PACK_TYPE"C0201"
MATERIAL"X7S"
VALUE"0.1UF"
VOLTAGE"10V"
TOLERANCE"10%"
CDS_LIB"pure_quanta"
PART_NUMBER"CH4102K6E00";
"B"
$PN"2"8;
"A"
$PN"1"7;
%"Q_CAP"
"1","(-5450,4000)","0","pure_quanta","I28";
;
LOCATION"C287"
$SEC"1"
CDS_SEC"1"
VOLTAGE"10V"
MATERIAL"X7S"
TOLERANCE"10%"
PACK_TYPE"C0201"
VALUE"0.1UF"
CDS_LIB"pure_quanta"
PART_NUMBER"CH4102K6E00";
"B"
$PN"2"8;
"A"
$PN"1"7;
%"Q_CAP"
"1","(-5175,4000)","0","pure_quanta","I29";
;
LOCATION"C288"
$SEC"1"
CDS_SEC"1"
VALUE"0.1UF"
MATERIAL"X7S"
TOLERANCE"10%"
PACK_TYPE"C0201"
VOLTAGE"10V"
CDS_LIB"pure_quanta"
PART_NUMBER"CH4102K6E00";
"B"
$PN"2"8;
"A"
$PN"1"7;
%"P1V0"
"1","(-8175,5100)","0","pure_quanta_power","I3";
;
HDL_POWER"P1V8_CPU1_RT_1D"
CDS_LIB"pure_quanta_power";
"A"5;
%"Q_INDUCTOR"
"1","(-3850,4275)","0","pure_quanta","I30";
;
LOCATION"L6"
$SEC"1"
CDS_SEC"1"
MATERIAL"IND"
PACK_TYPE"SMLF"
VALUE"100NH/16A"
NEEDS_NO_SIZE"TRUE"
CDS_LIB"pure_quanta"
PART_NUMBER"CV+10G0MZ04";
"1"
$PN"1"3;
"2"
$PN"2"1;
%"VCC_CORE"
"1","(-4325,5775)","0","pure_quanta_power","I31";
;
HDL_POWER"P0V9_CPU1_RT_2D"
CDS_LIB"pure_quanta_power";
"A"3;
%"VCC_CORE"
"1","(-3175,1475)","0","pure_quanta_power","I33";
;
HDL_POWER"P0V9_CPU1_RT1_2A_2D"
CDS_LIB"pure_quanta_power";
"A"13;
%"Q_CAP"
"1","(-2800,950)","0","pure_quanta","I34";
;
LOCATION"C313"
$SEC"1"
CDS_SEC"1"
PACK_TYPE"C0201"
TOLERANCE"10%"
MATERIAL"X7S"
VOLTAGE"10V"
VALUE"0.1UF"
CDS_LIB"pure_quanta"
PART_NUMBER"CH4102K6E00";
"B"
$PN"2"12;
"A"
$PN"1"13;
%"UNIVERSAL_GND"
"1","(-2350,625)","0","pure_quanta_power","I35";
;
CDS_LIB"pure_quanta_power"
HDL_POWER"GND";
"A"12;
%"Q_CAP"
"1","(-2250,950)","0","pure_quanta","I37";
;
LOCATION"C316"
$SEC"1"
CDS_SEC"1"
PACK_TYPE"C0201"
MATERIAL"X7S"
VOLTAGE"10V"
TOLERANCE"10%"
VALUE"0.1UF"
CDS_LIB"pure_quanta"
PART_NUMBER"CH4102K6E00";
"B"
$PN"2"12;
"A"
$PN"1"13;
%"Q_CAP"
"1","(-3225,2050)","0","pure_quanta","I38";
;
LOCATION"C340"
$SEC"1"
CDS_SEC"1"
VALUE"0.1UF"
MATERIAL"X7S"
PACK_TYPE"C0201"
VOLTAGE"10V"
TOLERANCE"10%"
CDS_LIB"pure_quanta"
PART_NUMBER"CH4102K6E00";
"B"
$PN"2"10;
"A"
$PN"1"1;
%"Q_CAP"
"1","(-2925,2050)","0","pure_quanta","I39";
;
LOCATION"C344"
$SEC"1"
CDS_SEC"1"
VALUE"0.1UF"
MATERIAL"X7S"
PACK_TYPE"C0201"
VOLTAGE"10V"
TOLERANCE"10%"
CDS_LIB"pure_quanta"
PART_NUMBER"CH4102K6E00";
"B"
$PN"2"10;
"A"
$PN"1"1;
%"Q_RES"
"1","(-7725,3375)","0","pure_quanta","I4";
;
LOCATION"R664"
SEC"1"
WATTAGE"1/16W"
TOLERANCE"5%"
PACK_TYPE"0402LF"
VALUE"0"
MATERIAL"EMPTY"
CDS_LIB"pure_quanta"
SEC_TYPE"0402LF"
PART_NUMBER"CS00002JB13";
"B"
$PN"2"7;
"A"
$PN"1"11;
%"Q_CAP"
"1","(-3500,2750)","0","pure_quanta","I40";
;
LOCATION"C294"
$SEC"1"
CDS_SEC"1"
VALUE"1UF"
VOLTAGE"4V"
PACK_TYPE"0201"
MATERIAL"X6S"
TOLERANCE"20%"
CDS_LIB"pure_quanta"
PART_NUMBER"CH-10KMEE00";
"B"
$PN"2"2;
"A"
$PN"1"1;
%"Q_CAP"
"1","(-3500,3375)","0","pure_quanta","I41";
;
LOCATION"C332"
$SEC"1"
CDS_SEC"1"
VOLTAGE"6.3V"
VALUE"10UF"
TOLERANCE"20%"
MATERIAL"X6S"
PACK_TYPE"C0402"
CDS_LIB"pure_quanta"
PART_NUMBER"CH6101MEB01";
"B"
$PN"2"2;
"A"
$PN"1"1;
%"Q_CAP"
"1","(-3275,2750)","0","pure_quanta","I42";
;
LOCATION"C307"
$SEC"1"
CDS_SEC"1"
VALUE"1UF"
TOLERANCE"20%"
PACK_TYPE"0201"
MATERIAL"X6S"
VOLTAGE"4V"
CDS_LIB"pure_quanta"
PART_NUMBER"CH-10KMEE00";
"B"
$PN"2"2;
"A"
$PN"1"1;
%"Q_CAP"
"1","(-3025,2750)","0","pure_quanta","I43";
;
LOCATION"C326"
$SEC"1"
CDS_SEC"1"
VALUE"1UF"
VOLTAGE"4V"
TOLERANCE"20%"
PACK_TYPE"0201"
MATERIAL"X6S"
CDS_LIB"pure_quanta"
PART_NUMBER"CH-10KMEE00";
"B"
$PN"2"2;
"A"
$PN"1"1;
%"Q_CAP"
"1","(-3275,3375)","0","pure_quanta","I44";
;
LOCATION"C321"
$SEC"1"
CDS_SEC"1"
MATERIAL"X6S"
VALUE"10UF"
PACK_TYPE"C0402"
TOLERANCE"20%"
VOLTAGE"6.3V"
CDS_LIB"pure_quanta"
PART_NUMBER"CH6101MEB01";
"B"
$PN"2"2;
"A"
$PN"1"1;
%"Q_CAP"
"1","(-3050,3375)","0","pure_quanta","I45";
;
LOCATION"C325"
$SEC"1"
CDS_SEC"1"
VOLTAGE"6.3V"
MATERIAL"X6S"
PACK_TYPE"0402"
VALUE"4.7UF"
TOLERANCE"20%"
CDS_LIB"pure_quanta"
PART_NUMBER"CH5471MEB01";
"B"
$PN"2"2;
"A"
$PN"1"1;
%"Q_CAP"
"1","(-2825,3375)","0","pure_quanta","I46";
;
LOCATION"C331"
$SEC"1"
CDS_SEC"1"
TOLERANCE"20%"
VOLTAGE"6.3V"
MATERIAL"X6S"
VALUE"4.7UF"
PACK_TYPE"0402"
CDS_LIB"pure_quanta"
PART_NUMBER"CH5471MEB01";
"B"
$PN"2"2;
"A"
$PN"1"1;
%"Q_CAP"
"1","(-2800,2750)","0","pure_quanta","I47";
;
LOCATION"C330"
$SEC"1"
CDS_SEC"1"
PACK_TYPE"0201"
MATERIAL"X6S"
VALUE"1UF"
VOLTAGE"4V"
TOLERANCE"20%"
CDS_LIB"pure_quanta"
PART_NUMBER"CH-10KMEE00";
"B"
$PN"2"2;
"A"
$PN"1"1;
%"Q_CAP"
"1","(-2700,2050)","0","pure_quanta","I48";
;
LOCATION"C312"
$SEC"1"
CDS_SEC"1"
VALUE"0.1UF"
VOLTAGE"10V"
PACK_TYPE"C0201"
MATERIAL"X7S"
TOLERANCE"10%"
CDS_LIB"pure_quanta"
PART_NUMBER"CH4102K6E00";
"B"
$PN"2"10;
"A"
$PN"1"1;
%"Q_CAP"
"1","(-2450,2050)","0","pure_quanta","I49";
;
LOCATION"C349"
$SEC"1"
CDS_SEC"1"
VALUE"0.1UF"
VOLTAGE"10V"
PACK_TYPE"C0201"
MATERIAL"X7S"
TOLERANCE"10%"
CDS_LIB"pure_quanta"
PART_NUMBER"CH4102K6E00";
"B"
$PN"2"10;
"A"
$PN"1"1;
%"Q_RES"
"1","(-7725,3575)","0","pure_quanta","I5";
;
LOCATION"R653"
SEC"1"
MATERIAL"EMPTY"
WATTAGE"1/16W"
PACK_TYPE"0402LF"
TOLERANCE"5%"
VALUE"0"
SEC_TYPE"0402LF"
CDS_LIB"pure_quanta"
PART_NUMBER"CS00002JB13";
"B"
$PN"2"7;
"A"
$PN"1"11;
%"Q_CAP"
"1","(-2200,2050)","0","pure_quanta","I50";
;
LOCATION"C291"
$SEC"1"
CDS_SEC"1"
PACK_TYPE"C0201"
MATERIAL"X7S"
TOLERANCE"10%"
VOLTAGE"10V"
VALUE"0.1UF"
CDS_LIB"pure_quanta"
PART_NUMBER"CH4102K6E00";
"B"
$PN"2"10;
"A"
$PN"1"1;
%"Q_CAP"
"1","(-1925,2050)","0","pure_quanta","I51";
;
LOCATION"C319"
$SEC"1"
CDS_SEC"1"
PACK_TYPE"C0201"
VOLTAGE"10V"
VALUE"0.1UF"
TOLERANCE"10%"
MATERIAL"X7S"
CDS_LIB"pure_quanta"
PART_NUMBER"CH4102K6E00";
"B"
$PN"2"10;
"A"
$PN"1"1;
%"Q_CAP"
"1","(-2550,2750)","0","pure_quanta","I52";
;
LOCATION"C314"
$SEC"1"
CDS_SEC"1"
VALUE"1UF"
PACK_TYPE"0201"
TOLERANCE"20%"
VOLTAGE"4V"
MATERIAL"X6S"
CDS_LIB"pure_quanta"
PART_NUMBER"CH-10KMEE00";
"B"
$PN"2"2;
"A"
$PN"1"1;
%"Q_CAP"
"1","(-2325,2725)","0","pure_quanta","I53";
;
LOCATION"C337"
$SEC"1"
CDS_SEC"1"
PACK_TYPE"0201"
VOLTAGE"4V"
MATERIAL"X6S"
TOLERANCE"20%"
VALUE"1UF"
CDS_LIB"pure_quanta"
PART_NUMBER"CH-10KMEE00";
"B"
$PN"2"2;
"A"
$PN"1"1;
%"Q_CAP"
"1","(-2575,3375)","0","pure_quanta","I54";
;
LOCATION"C343"
$SEC"1"
CDS_SEC"1"
MATERIAL"X6S"
VALUE"4.7UF"
PACK_TYPE"0402"
VOLTAGE"6.3V"
TOLERANCE"20%"
CDS_LIB"pure_quanta"
PART_NUMBER"CH5471MEB01";
"B"
$PN"2"2;
"A"
$PN"1"1;
%"Q_CAP"
"1","(-2350,3375)","0","pure_quanta","I55";
;
LOCATION"C336"
$SEC"1"
CDS_SEC"1"
TOLERANCE"20%"
PACK_TYPE"0402"
MATERIAL"X6S"
VALUE"4.7UF"
VOLTAGE"6.3V"
CDS_LIB"pure_quanta"
PART_NUMBER"CH5471MEB01";
"B"
$PN"2"2;
"A"
$PN"1"1;
%"Q_CAP"
"1","(-2075,2725)","0","pure_quanta","I57";
;
LOCATION"C346"
$SEC"1"
CDS_SEC"1"
MATERIAL"X6S"
PACK_TYPE"0201"
VALUE"1UF"
VOLTAGE"4V"
TOLERANCE"20%"
CDS_LIB"pure_quanta"
PART_NUMBER"CH-10KMEE00";
"B"
$PN"2"2;
"A"
$PN"1"1;
%"Q_CAP"
"1","(-2125,3375)","0","pure_quanta","I58";
;
LOCATION"C293"
$SEC"1"
CDS_SEC"1"
MATERIAL"X6S"
TOLERANCE"20%"
VALUE"1UF"
VOLTAGE"4V"
PACK_TYPE"0201"
CDS_LIB"pure_quanta"
PART_NUMBER"CH-10KMEE00";
"B"
$PN"2"2;
"A"
$PN"1"1;
%"Q_CAP"
"1","(-1900,3375)","0","pure_quanta","I59";
;
LOCATION"C301"
$SEC"1"
CDS_SEC"1"
PACK_TYPE"0201"
MATERIAL"X6S"
TOLERANCE"20%"
VOLTAGE"4V"
VALUE"1UF"
CDS_LIB"pure_quanta"
PART_NUMBER"CH-10KMEE00";
"B"
$PN"2"2;
"A"
$PN"1"1;
%"P1V0"
"1","(-6925,3300)","0","pure_quanta_power","I6";
;
HDL_POWER"P1V8_CPU1_RT1_1A_1D"
CDS_LIB"pure_quanta_power";
"A"11;
%"Q_CAP"
"1","(-1650,2050)","0","pure_quanta","I60";
;
LOCATION"C322"
$SEC"1"
CDS_SEC"1"
PACK_TYPE"C0201"
VALUE"0.1UF"
VOLTAGE"10V"
TOLERANCE"10%"
MATERIAL"X7S"
CDS_LIB"pure_quanta"
PART_NUMBER"CH4102K6E00";
"B"
$PN"2"10;
"A"
$PN"1"1;
%"UNIVERSAL_GND"
"1","(-1400,1625)","0","pure_quanta_power","I61";
;
CDS_LIB"pure_quanta_power"
HDL_POWER"GND";
"A"10;
%"Q_CAP"
"1","(-1400,2050)","0","pure_quanta","I62";
;
LOCATION"C334"
$SEC"1"
CDS_SEC"1"
PACK_TYPE"C0201"
TOLERANCE"10%"
VALUE"0.1UF"
VOLTAGE"10V"
MATERIAL"X7S"
CDS_LIB"pure_quanta"
PART_NUMBER"CH4102K6E00";
"B"
$PN"2"10;
"A"
$PN"1"1;
%"UNIVERSAL_GND"
"1","(-900,2325)","0","pure_quanta_power","I63";
;
CDS_LIB"pure_quanta_power"
HDL_POWER"GND";
"A"2;
%"Q_CAP"
"1","(-1675,3375)","0","pure_quanta","I65";
;
LOCATION"C289"
$SEC"1"
CDS_SEC"1"
PACK_TYPE"0201"
TOLERANCE"20%"
VOLTAGE"4V"
MATERIAL"X6S"
VALUE"1UF"
CDS_LIB"pure_quanta"
PART_NUMBER"CH-10KMEE00";
"B"
$PN"2"2;
"A"
$PN"1"1;
%"Q_CAP"
"1","(-1425,3375)","0","pure_quanta","I66";
;
LOCATION"C353"
$SEC"1"
CDS_SEC"1"
PACK_TYPE"0201"
TOLERANCE"20%"
VOLTAGE"4V"
MATERIAL"X6S"
VALUE"1UF"
CDS_LIB"pure_quanta"
PART_NUMBER"CH-10KMEE00";
"B"
$PN"2"2;
"A"
$PN"1"1;
%"Q_CAP"
"1","(-3500,4000)","0","pure_quanta","I67";
;
LOCATION"C317"
$SEC"1"
CDS_SEC"1"
MATERIAL"X6S"
PACK_TYPE"C0805"
VALUE"100UF"
VOLTAGE"4V"
TOLERANCE"20%"
CDS_LIB"pure_quanta"
PART_NUMBER"CH710KMEA01";
"B"
$PN"2"2;
"A"
$PN"1"1;
%"VCC_CORE"
"1","(-3500,4650)","0","pure_quanta_power","I68";
;
HDL_POWER"P0V9_CPU1_RT1_2A"
CDS_LIB"pure_quanta_power";
"A"1;
%"Q_CAP"
"1","(-3275,4000)","0","pure_quanta","I69";
;
LOCATION"C320"
$SEC"1"
CDS_SEC"1"
TOLERANCE"20%"
MATERIAL"X6S"
VOLTAGE"4V"
PACK_TYPE"C0805"
VALUE"100UF"
CDS_LIB"pure_quanta"
PART_NUMBER"CH710KMEA01";
"B"
$PN"2"2;
"A"
$PN"1"1;
%"UNIVERSAL_GND"
"1","(-6525,2500)","0","pure_quanta_power","I7";
;
CDS_LIB"pure_quanta_power"
HDL_POWER"GND";
"A"9;
%"Q_CAP"
"1","(-3050,4000)","0","pure_quanta","I70";
;
LOCATION"C324"
$SEC"1"
CDS_SEC"1"
PACK_TYPE"C0805"
TOLERANCE"20%"
VOLTAGE"4V"
MATERIAL"X6S"
VALUE"100UF"
CDS_LIB"pure_quanta"
PART_NUMBER"CH710KMEA01";
"B"
$PN"2"2;
"A"
$PN"1"1;
%"Q_CAP"
"1","(-2825,4000)","0","pure_quanta","I71";
;
LOCATION"C328"
$SEC"1"
CDS_SEC"1"
TOLERANCE"20%"
VALUE"100UF"
MATERIAL"X6S"
VOLTAGE"4V"
PACK_TYPE"C0805"
CDS_LIB"pure_quanta"
PART_NUMBER"CH710KMEA01";
"B"
$PN"2"2;
"A"
$PN"1"1;
%"Q_CAP"
"1","(-3450,5275)","0","pure_quanta","I72";
;
LOCATION"C323"
$SEC"1"
CDS_SEC"1"
VOLTAGE"4V"
TOLERANCE"20%"
PACK_TYPE"C0805"
MATERIAL"X6S"
VALUE"100UF"
CDS_LIB"pure_quanta"
PART_NUMBER"CH710KMEA01";
"B"
$PN"2"4;
"A"
$PN"1"3;
%"Q_CAP"
"1","(-3175,5275)","0","pure_quanta","I73";
;
LOCATION"C327"
$SEC"1"
CDS_SEC"1"
PACK_TYPE"C0402"
VALUE"22UF"
VOLTAGE"4V"
TOLERANCE"20%"
MATERIAL"X6S"
CDS_LIB"pure_quanta"
PART_NUMBER"CH622KMEB02";
"B"
$PN"2"4;
"A"
$PN"1"3;
%"Q_CAP"
"1","(-2575,4000)","0","pure_quanta","I74";
;
LOCATION"C329"
$SEC"1"
CDS_SEC"1"
VALUE"22UF"
TOLERANCE"20%"
MATERIAL"X6S"
PACK_TYPE"C0402"
VOLTAGE"4V"
CDS_LIB"pure_quanta"
PART_NUMBER"CH622KMEB02";
"B"
$PN"2"2;
"A"
$PN"1"1;
%"Q_CAP"
"1","(-2350,4000)","0","pure_quanta","I75";
;
LOCATION"C335"
$SEC"1"
CDS_SEC"1"
VALUE"22UF"
MATERIAL"X6S"
TOLERANCE"20%"
VOLTAGE"4V"
PACK_TYPE"C0402"
CDS_LIB"pure_quanta"
PART_NUMBER"CH622KMEB02";
"B"
$PN"2"2;
"A"
$PN"1"1;
%"Q_CAP"
"1","(-2125,4000)","0","pure_quanta","I76";
;
LOCATION"C351"
$SEC"1"
CDS_SEC"1"
PACK_TYPE"C0402"
VOLTAGE"4V"
VALUE"22UF"
TOLERANCE"20%"
MATERIAL"X6S"
CDS_LIB"pure_quanta"
PART_NUMBER"CH622KMEB02";
"B"
$PN"2"2;
"A"
$PN"1"1;
%"Q_CAP"
"1","(-1900,4000)","0","pure_quanta","I77";
;
LOCATION"C318"
$SEC"1"
CDS_SEC"1"
VALUE"22UF"
VOLTAGE"4V"
MATERIAL"X6S"
TOLERANCE"20%"
PACK_TYPE"C0402"
CDS_LIB"pure_quanta"
PART_NUMBER"CH622KMEB02";
"B"
$PN"2"2;
"A"
$PN"1"1;
%"Q_CAP"
"1","(-2550,5250)","0","pure_quanta","I78";
;
LOCATION"C338"
$SEC"1"
CDS_SEC"1"
PACK_TYPE"0402"
VALUE"4.7UF"
VOLTAGE"6.3V"
MATERIAL"X6S"
TOLERANCE"20%"
CDS_LIB"pure_quanta"
PART_NUMBER"CH5471MEB01";
"B"
$PN"2"4;
"A"
$PN"1"3;
%"Q_CAP"
"1","(-2250,5250)","0","pure_quanta","I79";
;
LOCATION"C342"
$SEC"1"
CDS_SEC"1"
PACK_TYPE"0201"
TOLERANCE"20%"
VALUE"1UF"
VOLTAGE"4V"
MATERIAL"X6S"
CDS_LIB"pure_quanta"
PART_NUMBER"CH-10KMEE00";
"B"
$PN"2"4;
"A"
$PN"1"3;
%"Q_CAP"
"1","(-6800,2925)","0","pure_quanta","I8";
;
LOCATION"C203"
$SEC"1"
CDS_SEC"1"
VOLTAGE"4V"
TOLERANCE"20%"
VALUE"1UF"
MATERIAL"X6S"
PACK_TYPE"0201"
CDS_LIB"pure_quanta"
PART_NUMBER"CH-10KMEE00";
"B"
$PN"2"9;
"A"
$PN"1"11;
%"Q_CAP"
"1","(-1600,4000)","0","pure_quanta","I80";
;
LOCATION"C339"
$SEC"1"
CDS_SEC"1"
PACK_TYPE"C0402"
MATERIAL"X6S"
VALUE"10UF"
VOLTAGE"6.3V"
TOLERANCE"20%"
CDS_LIB"pure_quanta"
PART_NUMBER"CH6101MEB01";
"B"
$PN"2"2;
"A"
$PN"1"1;
%"Q_CAP"
"1","(-1300,4000)","0","pure_quanta","I81";
;
LOCATION"C354"
$SEC"1"
CDS_SEC"1"
PACK_TYPE"C0402"
MATERIAL"X6S"
TOLERANCE"20%"
VOLTAGE"6.3V"
VALUE"10UF"
CDS_LIB"pure_quanta"
PART_NUMBER"CH6101MEB01";
"B"
$PN"2"2;
"A"
$PN"1"1;
%"Q_CAP"
"1","(-1425,5225)","0","pure_quanta","I82";
;
LOCATION"C300"
$SEC"1"
CDS_SEC"1"
MATERIAL"X7S"
VOLTAGE"10V"
VALUE"0.1UF"
TOLERANCE"10%"
PACK_TYPE"C0201"
CDS_LIB"pure_quanta"
PART_NUMBER"CH4102K6E00";
"B"
$PN"2"4;
"A"
$PN"1"3;
%"UNIVERSAL_GND"
"1","(-1225,4825)","0","pure_quanta_power","I83";
;
CDS_LIB"pure_quanta_power"
HDL_POWER"GND";
"A"4;
%"Q_CAP"
"1","(-1150,5225)","0","pure_quanta","I84";
;
LOCATION"C311"
$SEC"1"
CDS_SEC"1"
PACK_TYPE"C0201"
MATERIAL"X7S"
VOLTAGE"10V"
TOLERANCE"10%"
VALUE"0.1UF"
CDS_LIB"pure_quanta"
PART_NUMBER"CH4102K6E00";
"B"
$PN"2"4;
"A"
$PN"1"3;
%"Q_CAP"
"1","(-1675,5225)","0","pure_quanta","I85";
;
LOCATION"C292"
$SEC"1"
CDS_SEC"1"
PACK_TYPE"C0201"
MATERIAL"X7S"
VOLTAGE"10V"
TOLERANCE"10%"
VALUE"0.1UF"
CDS_LIB"pure_quanta"
PART_NUMBER"CH4102K6E00";
"B"
$PN"2"4;
"A"
$PN"1"3;
%"Q_CAP"
"1","(-1950,5225)","0","pure_quanta","I86";
;
LOCATION"C290"
$SEC"1"
CDS_SEC"1"
VOLTAGE"10V"
VALUE"0.1UF"
PACK_TYPE"C0201"
MATERIAL"X7S"
TOLERANCE"10%"
CDS_LIB"pure_quanta"
PART_NUMBER"CH4102K6E00";
"B"
$PN"2"4;
"A"
$PN"1"3;
%"Q_CAP"
"1","(-2850,5250)","0","pure_quanta","I87";
;
LOCATION"C333"
$SEC"1"
CDS_SEC"1"
PACK_TYPE"C0402"
MATERIAL"X6S"
VOLTAGE"6.3V"
TOLERANCE"20%"
VALUE"10UF"
CDS_LIB"pure_quanta"
PART_NUMBER"CH6101MEB01";
"B"
$PN"2"4;
"A"
$PN"1"3;
%"Q_INDUCTOR"
"1","(-8250,3925)","3","pure_quanta","I88";
;
LOCATION"L31"
$SEC"1"
CDS_SEC"1"
PACK_TYPE"SMLF"
MATERIAL"IND"
VALUE"BLM15PD121SN1D/1300MA"
NEEDS_NO_SIZE"TRUE"
CDS_LIB"pure_quanta"
PART_NUMBER"CX5PD121000";
"1"
$PN"1"5;
"2"
$PN"2"11;
%"Q_RES"
"2","(-8125,3900)","0","pure_quanta","I89";
;
LOCATION"R704"
$SEC"1"
CDS_SEC"1"
VALUE"0"
MATERIAL"EMPTY"
TOLERANCE"5%"
PACK_TYPE"0402LF"
WATTAGE"1/16W"
CDS_LIB"pure_quanta"
PART_NUMBER"CS00002JB13";
"A"
$PN"1"5;
"B"
$PN"2"11;
%"Q_CAP"
"1","(-6525,2900)","0","pure_quanta","I9";
;
LOCATION"C206"
$SEC"1"
CDS_SEC"1"
PACK_TYPE"C0201"
MATERIAL"X7S"
VOLTAGE"10V"
VALUE"0.1UF"
TOLERANCE"10%"
CDS_LIB"pure_quanta"
PART_NUMBER"CH4102K6E00";
"B"
$PN"2"9;
"A"
$PN"1"11;
%"Q_CAP"
"1","(-3050,950)","0","pure_quanta","I90";
;
LOCATION"C306"
$SEC"1"
CDS_SEC"1"
PACK_TYPE"0201"
MATERIAL"X6S"
TOLERANCE"20%"
VALUE"1UF"
VOLTAGE"4V"
CDS_LIB"pure_quanta"
PART_NUMBER"CH-10KMEE00";
"B"
$PN"2"12;
"A"
$PN"1"13;
%"Q_CAP"
"1","(-2500,950)","0","pure_quanta","I91";
;
LOCATION"C315"
$SEC"1"
CDS_SEC"1"
VALUE"1UF"
VOLTAGE"4V"
TOLERANCE"20%"
MATERIAL"X6S"
PACK_TYPE"0201"
CDS_LIB"pure_quanta"
PART_NUMBER"CH-10KMEE00";
"B"
$PN"2"12;
"A"
$PN"1"13;
%"Q_CAP"
"1","(-1825,2750)","0","pure_quanta","I92";
;
LOCATION"C341"
$SEC"1"
CDS_SEC"1"
VALUE"0.1UF"
MATERIAL"X7S"
TOLERANCE"10%"
VOLTAGE"10V"
PACK_TYPE"C0201"
CDS_LIB"pure_quanta"
PART_NUMBER"CH4102K6E00";
"B"
$PN"2"2;
"A"
$PN"1"1;
%"Q_CAP"
"1","(-1550,2750)","0","pure_quanta","I93";
;
LOCATION"C350"
$SEC"1"
CDS_SEC"1"
TOLERANCE"10%"
PACK_TYPE"C0201"
MATERIAL"X7S"
VOLTAGE"10V"
VALUE"0.1UF"
CDS_LIB"pure_quanta"
PART_NUMBER"CH4102K6E00";
"B"
$PN"2"2;
"A"
$PN"1"1;
%"Q_CAPP"
"1","(-1100,2050)","0","pure_quanta","I94";
;
LOCATION"C7023"
$SEC"1"
CDS_SEC"1"
TOLERANCE"20%"
PACK_TYPE"SMLF"
MATERIAL"SPCAP"
VALUE"470UF"
VOLTAGE"2.5V"
CDS_LIB"pure_quanta"
PART_NUMBER"CH747LM8818";
"A"
$PN"1"1;
"B"
$PN"2"10;
%"Q_CAPP"
"1","(-800,2050)","0","pure_quanta","I95";
;
LOCATION"C7024"
$SEC"1"
CDS_SEC"1"
MATERIAL"SPCAP"
PACK_TYPE"SMLF"
VALUE"470UF"
TOLERANCE"20%"
VOLTAGE"2.5V"
CDS_LIB"pure_quanta"
PART_NUMBER"CH747LM8818";
"A"
$PN"1"1;
"B"
$PN"2"10;
%"Q_CAP"
"1","(-500,2050)","0","pure_quanta","I96";
;
LOCATION"C7025"
$SEC"1"
CDS_SEC"1"
PACK_TYPE"C0805"
MATERIAL"X6S"
TOLERANCE"20%"
VALUE"100UF"
VOLTAGE"4V"
CDS_LIB"pure_quanta"
PART_NUMBER"CH710KMEA01";
"B"
$PN"2"10;
"A"
$PN"1"1;
END.
